(kicad_pcb
	(version 20260206)
	(generator "pcbnew")
	(generator_version "10.0")
	(general
		(thickness 1.6)
		(legacy_teardrops no)
	)
	(paper "A4")
	(title_block
		(title "01162023_DA0F0TEBIF0_F0T_Expander_BD_F_brd_V02_OCP.brd")
		(comment 1 "Grand Teton / footprints 8581-8589 of 9728")
	)
	(layers
		(0 "F.Cu" signal "TOP")
		(4 "In1.Cu" signal "GND")
		(6 "In2.Cu" signal "VCC")
		(8 "In3.Cu" signal "VCC1")
		(10 "In4.Cu" signal "GND1")
		(12 "In5.Cu" signal "IN1")
		(14 "In6.Cu" signal "GND2")
		(16 "In7.Cu" signal "IN2")
		(18 "In8.Cu" signal "GND3")
		(20 "In9.Cu" signal "IN3")
		(22 "In10.Cu" signal "GND4")
		(24 "In11.Cu" signal "IN4")
		(26 "In12.Cu" signal "GND5")
		(28 "In13.Cu" signal "IN5")
		(30 "In14.Cu" signal "GND6")
		(32 "In15.Cu" signal "IN6")
		(34 "In16.Cu" signal "GND7")
		(2 "B.Cu" signal "BOTTOM")
		(9 "F.Adhes" user "F.Adhesive")
		(11 "B.Adhes" user "B.Adhesive")
		(13 "F.Paste" user "Package Geometry/Pastemask Top")
		(15 "B.Paste" user "Package Geometry/Pastemask Bottom")
		(5 "F.SilkS" user "Ref Des/Silkscreen Top")
		(7 "B.SilkS" user "Ref Des/Silkscreen Bottom")
		(1 "F.Mask" user "Board Geometry/Soldermask Top")
		(3 "B.Mask" user "Board Geometry/Soldermask Bottom")
		(17 "Dwgs.User" user "User.Drawings")
		(19 "Cmts.User" user "User.Comments")
		(21 "Eco1.User" user "User.Eco1")
		(23 "Eco2.User" user "User.Eco2")
		(25 "Edge.Cuts" user "Board Geometry/Outline")
		(27 "Margin" user)
		(31 "F.CrtYd" user "Package Geometry/Place Bound Top")
		(29 "B.CrtYd" user "Package Geometry/Place Bound Bottom")
		(35 "F.Fab" user "Ref Des/Assembly Top")
		(33 "B.Fab" user "Ref Des/Assembly Bottom")
	)
	(footprint ""
		(layer "B.Cu")
		(at 64.399922 -301.599854 -90)
		(property "Reference" "C1204"
			(at 0 0 90)
			(layer "B.SilkS")
			(hide yes)
			(effects
				(font
					(size 1.27 1.27)
				)
				(justify mirror)
			)
		)
		(property "Value" ""
			(at 0 0 90)
			(layer "B.Fab")
			(effects
				(font
					(size 1.27 1.27)
				)
				(justify mirror)
			)
		)
		(duplicate_pad_numbers_are_jumpers no)
		(fp_line
			(start -0.299974 0.150114)
			(end 0.299974 0.150114)
			(stroke
				(width 0.1)
				(type default)
			)
			(layer "B.Fab")
		)
		(fp_line
			(start 0.299974 0.150114)
			(end 0.299974 -0.150114)
			(stroke
				(width 0.1)
				(type default)
			)
			(layer "B.Fab")
		)
		(fp_line
			(start -0.299974 -0.150114)
			(end -0.299974 0.150114)
			(stroke
				(width 0.1)
				(type default)
			)
			(layer "B.Fab")
		)
		(fp_line
			(start 0.299974 -0.150114)
			(end -0.299974 -0.150114)
			(stroke
				(width 0.1)
				(type default)
			)
			(layer "B.Fab")
		)
		(pad "1" smd rect
			(at 0.2667 0 90)
			(size 0.3048 0.381)
			(layers "B.Cu" "B.Mask" "B.Paste")
			(net "P0V8_SERDES_VDDA_PEX0")
		)
		(pad "2" smd rect
			(at -0.2667 0 90)
			(size 0.3048 0.381)
			(layers "B.Cu" "B.Mask" "B.Paste")
			(net "GND")
		)
	)
	(footprint ""
		(layer "B.Cu")
		(at 227.776024 -272.92554 180)
		(property "Reference" "C4274"
			(at 0 0 0)
			(layer "B.SilkS")
			(hide yes)
			(effects
				(font
					(size 1.27 1.27)
				)
				(justify mirror)
			)
		)
		(property "Value" ""
			(at 0 0 0)
			(layer "B.Fab")
			(effects
				(font
					(size 1.27 1.27)
				)
				(justify mirror)
			)
		)
		(duplicate_pad_numbers_are_jumpers no)
		(fp_line
			(start 1.2954 0.5842)
			(end 1.2954 -0.5842)
			(stroke
				(width 0.1524)
				(type default)
			)
			(layer "B.SilkS")
		)
		(fp_line
			(start 1.2954 -0.5842)
			(end -1.2954 -0.5842)
			(stroke
				(width 0.1524)
				(type default)
			)
			(layer "B.SilkS")
		)
		(fp_line
			(start -1.2954 0.5842)
			(end 1.2954 0.5842)
			(stroke
				(width 0.1524)
				(type default)
			)
			(layer "B.SilkS")
		)
		(fp_line
			(start -1.2954 -0.5842)
			(end -1.2954 0.5842)
			(stroke
				(width 0.1524)
				(type default)
			)
			(layer "B.SilkS")
		)
		(fp_line
			(start 1.1938 0.4064)
			(end 1.1938 -0.4064)
			(stroke
				(width 0.1)
				(type default)
			)
			(layer "B.Fab")
		)
		(fp_line
			(start 1.1938 -0.4064)
			(end 0.8636 -0.4064)
			(stroke
				(width 0.1)
				(type default)
			)
			(layer "B.Fab")
		)
		(fp_line
			(start 0.8636 0.4572)
			(end 0.8636 0.4064)
			(stroke
				(width 0.1)
				(type default)
			)
			(layer "B.Fab")
		)
		(fp_line
			(start 0.8636 0.4064)
			(end 1.1938 0.4064)
			(stroke
				(width 0.1)
				(type default)
			)
			(layer "B.Fab")
		)
		(fp_line
			(start 0.8636 -0.4064)
			(end 0.8636 -0.4572)
			(stroke
				(width 0.1)
				(type default)
			)
			(layer "B.Fab")
		)
		(fp_line
			(start 0.8636 -0.4572)
			(end -0.8636 -0.4572)
			(stroke
				(width 0.1)
				(type default)
			)
			(layer "B.Fab")
		)
		(fp_line
			(start -0.8636 0.4572)
			(end 0.8636 0.4572)
			(stroke
				(width 0.1)
				(type default)
			)
			(layer "B.Fab")
		)
		(fp_line
			(start -0.8636 0.4064)
			(end -0.8636 0.4572)
			(stroke
				(width 0.1)
				(type default)
			)
			(layer "B.Fab")
		)
		(fp_line
			(start -0.8636 -0.4064)
			(end -1.1938 -0.4064)
			(stroke
				(width 0.1)
				(type default)
			)
			(layer "B.Fab")
		)
		(fp_line
			(start -0.8636 -0.4572)
			(end -0.8636 -0.4064)
			(stroke
				(width 0.1)
				(type default)
			)
			(layer "B.Fab")
		)
		(fp_line
			(start -1.1938 0.4064)
			(end -0.8636 0.4064)
			(stroke
				(width 0.1)
				(type default)
			)
			(layer "B.Fab")
		)
		(fp_line
			(start -1.1938 -0.4064)
			(end -1.1938 0.4064)
			(stroke
				(width 0.1)
				(type default)
			)
			(layer "B.Fab")
		)
		(pad "1" smd rect
			(at 0.7366 0 90)
			(size 0.7112 0.8128)
			(layers "B.Cu" "B.Mask" "B.Paste")
			(net "P1V25_PEX1")
		)
		(pad "2" smd rect
			(at -0.7366 0 90)
			(size 0.7112 0.8128)
			(layers "B.Cu" "B.Mask" "B.Paste")
			(net "GND")
		)
	)
	(footprint ""
		(layer "B.Cu")
		(at 339.327744 -323.15531 -90)
		(property "Reference" "R6506"
			(at 0 0 90)
			(layer "B.SilkS")
			(hide yes)
			(effects
				(font
					(size 1.27 1.27)
				)
				(justify mirror)
			)
		)
		(property "Value" ""
			(at 0 0 90)
			(layer "B.Fab")
			(effects
				(font
					(size 1.27 1.27)
				)
				(justify mirror)
			)
		)
		(duplicate_pad_numbers_are_jumpers no)
		(fp_line
			(start -0.7874 0.4064)
			(end 0.7874 0.4064)
			(stroke
				(width 0.1524)
				(type default)
			)
			(layer "B.SilkS")
		)
		(fp_line
			(start 0.7874 0.4064)
			(end 0.7874 -0.4064)
			(stroke
				(width 0.1524)
				(type default)
			)
			(layer "B.SilkS")
		)
		(fp_line
			(start -0.7874 -0.4064)
			(end -0.7874 0.4064)
			(stroke
				(width 0.1524)
				(type default)
			)
			(layer "B.SilkS")
		)
		(fp_line
			(start 0.7874 -0.4064)
			(end -0.7874 -0.4064)
			(stroke
				(width 0.1524)
				(type default)
			)
			(layer "B.SilkS")
		)
		(fp_line
			(start -0.67945 0.3048)
			(end -0.120396 0.3048)
			(stroke
				(width 0.1)
				(type default)
			)
			(layer "B.Fab")
		)
		(fp_line
			(start -0.120396 0.3048)
			(end -0.120396 0.2794)
			(stroke
				(width 0.1)
				(type default)
			)
			(layer "B.Fab")
		)
		(fp_line
			(start 0.12065 0.3048)
			(end 0.67945 0.3048)
			(stroke
				(width 0.1)
				(type default)
			)
			(layer "B.Fab")
		)
		(fp_line
			(start 0.67945 0.3048)
			(end 0.67945 -0.305054)
			(stroke
				(width 0.1)
				(type default)
			)
			(layer "B.Fab")
		)
		(fp_line
			(start -0.120396 0.2794)
			(end 0.12065 0.2794)
			(stroke
				(width 0.1)
				(type default)
			)
			(layer "B.Fab")
		)
		(fp_line
			(start 0.12065 0.2794)
			(end 0.12065 0.3048)
			(stroke
				(width 0.1)
				(type default)
			)
			(layer "B.Fab")
		)
		(fp_line
			(start -0.12065 -0.2794)
			(end -0.12065 -0.3048)
			(stroke
				(width 0.1)
				(type default)
			)
			(layer "B.Fab")
		)
		(fp_line
			(start 0.12065 -0.2794)
			(end -0.12065 -0.2794)
			(stroke
				(width 0.1)
				(type default)
			)
			(layer "B.Fab")
		)
		(fp_line
			(start -0.67945 -0.3048)
			(end -0.67945 0.3048)
			(stroke
				(width 0.1)
				(type default)
			)
			(layer "B.Fab")
		)
		(fp_line
			(start -0.12065 -0.3048)
			(end -0.67945 -0.3048)
			(stroke
				(width 0.1)
				(type default)
			)
			(layer "B.Fab")
		)
		(fp_line
			(start 0.12065 -0.305054)
			(end 0.12065 -0.2794)
			(stroke
				(width 0.1)
				(type default)
			)
			(layer "B.Fab")
		)
		(fp_line
			(start 0.67945 -0.305054)
			(end 0.12065 -0.305054)
			(stroke
				(width 0.1)
				(type default)
			)
			(layer "B.Fab")
		)
		(pad "1" smd circle
			(at 0.40005 0 90)
			(size 0 0)
			(layers "B.Cu" "B.Mask" "B.Paste")
			(net "P0V8_SERDES_VDDA_PEX2")
		)
		(pad "2" smd circle
			(at -0.40005 0 90)
			(size 0 0)
			(layers "B.Cu" "B.Mask" "B.Paste")
			(net "P0V8_SERDES_VDDA_PEX2_C1")
		)
	)
	(footprint ""
		(layer "B.Cu")
		(at 394.42644 -140.8176 180)
		(property "Reference" "C942"
			(at 0 0 0)
			(layer "B.SilkS")
			(hide yes)
			(effects
				(font
					(size 1.27 1.27)
				)
				(justify mirror)
			)
		)
		(property "Value" ""
			(at 0 0 0)
			(layer "B.Fab")
			(effects
				(font
					(size 1.27 1.27)
				)
				(justify mirror)
			)
		)
		(duplicate_pad_numbers_are_jumpers no)
		(fp_line
			(start 0.7874 0.4064)
			(end 0.7874 -0.4064)
			(stroke
				(width 0.1524)
				(type default)
			)
			(layer "B.SilkS")
		)
		(fp_line
			(start 0.7874 -0.4064)
			(end -0.7874 -0.4064)
			(stroke
				(width 0.1524)
				(type default)
			)
			(layer "B.SilkS")
		)
		(fp_line
			(start -0.7874 0.4064)
			(end 0.7874 0.4064)
			(stroke
				(width 0.1524)
				(type default)
			)
			(layer "B.SilkS")
		)
		(fp_line
			(start -0.7874 -0.4064)
			(end -0.7874 0.4064)
			(stroke
				(width 0.1524)
				(type default)
			)
			(layer "B.SilkS")
		)
		(fp_line
			(start 0.67945 0.3048)
			(end 0.67945 -0.305054)
			(stroke
				(width 0.1)
				(type default)
			)
			(layer "B.Fab")
		)
		(fp_line
			(start 0.67945 -0.305054)
			(end 0.12065 -0.305054)
			(stroke
				(width 0.1)
				(type default)
			)
			(layer "B.Fab")
		)
		(fp_line
			(start 0.12065 0.3048)
			(end 0.67945 0.3048)
			(stroke
				(width 0.1)
				(type default)
			)
			(layer "B.Fab")
		)
		(fp_line
			(start 0.12065 0.2794)
			(end 0.12065 0.3048)
			(stroke
				(width 0.1)
				(type default)
			)
			(layer "B.Fab")
		)
		(fp_line
			(start 0.12065 -0.2794)
			(end -0.12065 -0.2794)
			(stroke
				(width 0.1)
				(type default)
			)
			(layer "B.Fab")
		)
		(fp_line
			(start 0.12065 -0.305054)
			(end 0.12065 -0.2794)
			(stroke
				(width 0.1)
				(type default)
			)
			(layer "B.Fab")
		)
		(fp_line
			(start -0.120396 0.3048)
			(end -0.120396 0.2794)
			(stroke
				(width 0.1)
				(type default)
			)
			(layer "B.Fab")
		)
		(fp_line
			(start -0.120396 0.2794)
			(end 0.12065 0.2794)
			(stroke
				(width 0.1)
				(type default)
			)
			(layer "B.Fab")
		)
		(fp_line
			(start -0.12065 -0.2794)
			(end -0.12065 -0.3048)
			(stroke
				(width 0.1)
				(type default)
			)
			(layer "B.Fab")
		)
		(fp_line
			(start -0.12065 -0.3048)
			(end -0.67945 -0.3048)
			(stroke
				(width 0.1)
				(type default)
			)
			(layer "B.Fab")
		)
		(fp_line
			(start -0.67945 0.3048)
			(end -0.120396 0.3048)
			(stroke
				(width 0.1)
				(type default)
			)
			(layer "B.Fab")
		)
		(fp_line
			(start -0.67945 -0.3048)
			(end -0.67945 0.3048)
			(stroke
				(width 0.1)
				(type default)
			)
			(layer "B.Fab")
		)
		(pad "1" smd circle
			(at 0.40005 0)
			(size 0 0)
			(layers "B.Cu" "B.Mask" "B.Paste")
			(net "P3V3_NIC6")
		)
		(pad "2" smd circle
			(at -0.40005 0)
			(size 0 0)
			(layers "B.Cu" "B.Mask" "B.Paste")
			(net "GND")
		)
	)
	(footprint ""
		(layer "B.Cu")
		(at 51.145694 -296.37482)
		(property "Reference" "C1129"
			(at 0 0 0)
			(layer "B.SilkS")
			(hide yes)
			(effects
				(font
					(size 1.27 1.27)
				)
				(justify mirror)
			)
		)
		(property "Value" ""
			(at 0 0 0)
			(layer "B.Fab")
			(effects
				(font
					(size 1.27 1.27)
				)
				(justify mirror)
			)
		)
		(duplicate_pad_numbers_are_jumpers no)
		(fp_line
			(start -0.299974 -0.150114)
			(end -0.299974 0.150114)
			(stroke
				(width 0.1)
				(type default)
			)
			(layer "B.Fab")
		)
		(fp_line
			(start -0.299974 0.150114)
			(end 0.299974 0.150114)
			(stroke
				(width 0.1)
				(type default)
			)
			(layer "B.Fab")
		)
		(fp_line
			(start 0.299974 -0.150114)
			(end -0.299974 -0.150114)
			(stroke
				(width 0.1)
				(type default)
			)
			(layer "B.Fab")
		)
		(fp_line
			(start 0.299974 0.150114)
			(end 0.299974 -0.150114)
			(stroke
				(width 0.1)
				(type default)
			)
			(layer "B.Fab")
		)
		(pad "1" smd rect
			(at 0.2667 0 180)
			(size 0.3048 0.381)
			(layers "B.Cu" "B.Mask" "B.Paste")
			(net "P0V8_PEX0")
		)
		(pad "2" smd rect
			(at -0.2667 0 180)
			(size 0.3048 0.381)
			(layers "B.Cu" "B.Mask" "B.Paste")
			(net "GND")
		)
	)
	(footprint ""
		(layer "B.Cu")
		(at 276.649688 -294.94988)
		(property "Reference" "C3348"
			(at 0 0 0)
			(layer "B.SilkS")
			(hide yes)
			(effects
				(font
					(size 1.27 1.27)
				)
				(justify mirror)
			)
		)
		(property "Value" ""
			(at 0 0 0)
			(layer "B.Fab")
			(effects
				(font
					(size 1.27 1.27)
				)
				(justify mirror)
			)
		)
		(duplicate_pad_numbers_are_jumpers no)
		(fp_line
			(start -0.299974 -0.150114)
			(end -0.299974 0.150114)
			(stroke
				(width 0.1)
				(type default)
			)
			(layer "B.Fab")
		)
		(fp_line
			(start -0.299974 0.150114)
			(end 0.299974 0.150114)
			(stroke
				(width 0.1)
				(type default)
			)
			(layer "B.Fab")
		)
		(fp_line
			(start 0.299974 -0.150114)
			(end -0.299974 -0.150114)
			(stroke
				(width 0.1)
				(type default)
			)
			(layer "B.Fab")
		)
		(fp_line
			(start 0.299974 0.150114)
			(end 0.299974 -0.150114)
			(stroke
				(width 0.1)
				(type default)
			)
			(layer "B.Fab")
		)
		(pad "1" smd rect
			(at 0.2667 0 180)
			(size 0.3048 0.381)
			(layers "B.Cu" "B.Mask" "B.Paste")
			(net "P1V8_PEX")
		)
		(pad "2" smd rect
			(at -0.2667 0 180)
			(size 0.3048 0.381)
			(layers "B.Cu" "B.Mask" "B.Paste")
			(net "GND")
		)
	)
	(footprint ""
		(layer "B.Cu")
		(at 63.449962 -299.699934 -90)
		(property "Reference" "C1232"
			(at 0 0 90)
			(layer "B.SilkS")
			(hide yes)
			(effects
				(font
					(size 1.27 1.27)
				)
				(justify mirror)
			)
		)
		(property "Value" ""
			(at 0 0 90)
			(layer "B.Fab")
			(effects
				(font
					(size 1.27 1.27)
				)
				(justify mirror)
			)
		)
		(duplicate_pad_numbers_are_jumpers no)
		(fp_line
			(start -0.299974 0.150114)
			(end 0.299974 0.150114)
			(stroke
				(width 0.1)
				(type default)
			)
			(layer "B.Fab")
		)
		(fp_line
			(start 0.299974 0.150114)
			(end 0.299974 -0.150114)
			(stroke
				(width 0.1)
				(type default)
			)
			(layer "B.Fab")
		)
		(fp_line
			(start -0.299974 -0.150114)
			(end -0.299974 0.150114)
			(stroke
				(width 0.1)
				(type default)
			)
			(layer "B.Fab")
		)
		(fp_line
			(start 0.299974 -0.150114)
			(end -0.299974 -0.150114)
			(stroke
				(width 0.1)
				(type default)
			)
			(layer "B.Fab")
		)
		(pad "1" smd rect
			(at 0.2667 0 90)
			(size 0.3048 0.381)
			(layers "B.Cu" "B.Mask" "B.Paste")
			(net "P0V8_SERDES_VDDA_PEX0")
		)
		(pad "2" smd rect
			(at -0.2667 0 90)
			(size 0.3048 0.381)
			(layers "B.Cu" "B.Mask" "B.Paste")
			(net "GND")
		)
	)
	(footprint ""
		(layer "B.Cu")
		(at 283.299916 -303.499774 -90)
		(property "Reference" "C3264"
			(at 0 0 90)
			(layer "B.SilkS")
			(hide yes)
			(effects
				(font
					(size 1.27 1.27)
				)
				(justify mirror)
			)
		)
		(property "Value" ""
			(at 0 0 90)
			(layer "B.Fab")
			(effects
				(font
					(size 1.27 1.27)
				)
				(justify mirror)
			)
		)
		(duplicate_pad_numbers_are_jumpers no)
		(fp_line
			(start -0.299974 0.150114)
			(end 0.299974 0.150114)
			(stroke
				(width 0.1)
				(type default)
			)
			(layer "B.Fab")
		)
		(fp_line
			(start 0.299974 0.150114)
			(end 0.299974 -0.150114)
			(stroke
				(width 0.1)
				(type default)
			)
			(layer "B.Fab")
		)
		(fp_line
			(start -0.299974 -0.150114)
			(end -0.299974 0.150114)
			(stroke
				(width 0.1)
				(type default)
			)
			(layer "B.Fab")
		)
		(fp_line
			(start 0.299974 -0.150114)
			(end -0.299974 -0.150114)
			(stroke
				(width 0.1)
				(type default)
			)
			(layer "B.Fab")
		)
		(pad "1" smd rect
			(at 0.2667 0 90)
			(size 0.3048 0.381)
			(layers "B.Cu" "B.Mask" "B.Paste")
			(net "P1V25_PEX2")
		)
		(pad "2" smd rect
			(at -0.2667 0 90)
			(size 0.3048 0.381)
			(layers "B.Cu" "B.Mask" "B.Paste")
			(net "GND")
		)
	)
	(footprint ""
		(layer "B.Cu")
		(at 371.475 -228.346 90)
		(property "Reference" "R3499"
			(at 0 0 90)
			(layer "B.SilkS")
			(hide yes)
			(effects
				(font
					(size 1.27 1.27)
				)
				(justify mirror)
			)
		)
		(property "Value" ""
			(at 0 0 90)
			(layer "B.Fab")
			(effects
				(font
					(size 1.27 1.27)
				)
				(justify mirror)
			)
		)
		(duplicate_pad_numbers_are_jumpers no)
		(fp_line
			(start 0.7874 -0.4064)
			(end -0.7874 -0.4064)
			(stroke
				(width 0.1524)
				(type default)
			)
			(layer "B.SilkS")
		)
		(fp_line
			(start -0.7874 -0.4064)
			(end -0.7874 0.4064)
			(stroke
				(width 0.1524)
				(type default)
			)
			(layer "B.SilkS")
		)
		(fp_line
			(start 0.7874 0.4064)
			(end 0.7874 -0.4064)
			(stroke
				(width 0.1524)
				(type default)
			)
			(layer "B.SilkS")
		)
		(fp_line
			(start -0.7874 0.4064)
			(end 0.7874 0.4064)
			(stroke
				(width 0.1524)
				(type default)
			)
			(layer "B.SilkS")
		)
		(fp_line
			(start 0.67945 -0.305054)
			(end 0.12065 -0.305054)
			(stroke
				(width 0.1)
				(type default)
			)
			(layer "B.Fab")
		)
		(fp_line
			(start 0.12065 -0.305054)
			(end 0.12065 -0.2794)
			(stroke
				(width 0.1)
				(type default)
			)
			(layer "B.Fab")
		)
		(fp_line
			(start -0.12065 -0.3048)
			(end -0.67945 -0.3048)
			(stroke
				(width 0.1)
				(type default)
			)
			(layer "B.Fab")
		)
		(fp_line
			(start -0.67945 -0.3048)
			(end -0.67945 0.3048)
			(stroke
				(width 0.1)
				(type default)
			)
			(layer "B.Fab")
		)
		(fp_line
			(start 0.12065 -0.2794)
			(end -0.12065 -0.2794)
			(stroke
				(width 0.1)
				(type default)
			)
			(layer "B.Fab")
		)
		(fp_line
			(start -0.12065 -0.2794)
			(end -0.12065 -0.3048)
			(stroke
				(width 0.1)
				(type default)
			)
			(layer "B.Fab")
		)
		(fp_line
			(start 0.12065 0.2794)
			(end 0.12065 0.3048)
			(stroke
				(width 0.1)
				(type default)
			)
			(layer "B.Fab")
		)
		(fp_line
			(start -0.120396 0.2794)
			(end 0.12065 0.2794)
			(stroke
				(width 0.1)
				(type default)
			)
			(layer "B.Fab")
		)
		(fp_line
			(start 0.67945 0.3048)
			(end 0.67945 -0.305054)
			(stroke
				(width 0.1)
				(type default)
			)
			(layer "B.Fab")
		)
		(fp_line
			(start 0.12065 0.3048)
			(end 0.67945 0.3048)
			(stroke
				(width 0.1)
				(type default)
			)
			(layer "B.Fab")
		)
		(fp_line
			(start -0.120396 0.3048)
			(end -0.120396 0.2794)
			(stroke
				(width 0.1)
				(type default)
			)
			(layer "B.Fab")
		)
		(fp_line
			(start -0.67945 0.3048)
			(end -0.120396 0.3048)
			(stroke
				(width 0.1)
				(type default)
			)
			(layer "B.Fab")
		)
		(pad "1" smd circle
			(at 0.40005 0 270)
			(size 0 0)
			(layers "B.Cu" "B.Mask" "B.Paste")
			(net "SPI_PEX3_SDIO1_MUX_R")
		)
		(pad "2" smd circle
			(at -0.40005 0 270)
			(size 0 0)
			(layers "B.Cu" "B.Mask" "B.Paste")
			(net "SPI_PEX3_SDIO1_MUX")
		)
	)
)
